(kicad_pcb
	(version 20260206)
	(generator "pcbnew")
	(generator_version "10.0")
	(general
		(thickness 1.6)
		(legacy_teardrops no)
	)
	(paper "A4")
	(title_block
		(title "01162023_DA0F0TEBIF0_F0T_Expander_BD_F_brd_V02_OCP.brd")
		(comment 1 "Grand Teton / footprints 955-957 of 9728")
	)
	(layers
		(0 "F.Cu" signal "TOP")
		(4 "In1.Cu" signal "GND")
		(6 "In2.Cu" signal "VCC")
		(8 "In3.Cu" signal "VCC1")
		(10 "In4.Cu" signal "GND1")
		(12 "In5.Cu" signal "IN1")
		(14 "In6.Cu" signal "GND2")
		(16 "In7.Cu" signal "IN2")
		(18 "In8.Cu" signal "GND3")
		(20 "In9.Cu" signal "IN3")
		(22 "In10.Cu" signal "GND4")
		(24 "In11.Cu" signal "IN4")
		(26 "In12.Cu" signal "GND5")
		(28 "In13.Cu" signal "IN5")
		(30 "In14.Cu" signal "GND6")
		(32 "In15.Cu" signal "IN6")
		(34 "In16.Cu" signal "GND7")
		(2 "B.Cu" signal "BOTTOM")
		(9 "F.Adhes" user "F.Adhesive")
		(11 "B.Adhes" user "B.Adhesive")
		(13 "F.Paste" user "Package Geometry/Pastemask Top")
		(15 "B.Paste" user "Package Geometry/Pastemask Bottom")
		(5 "F.SilkS" user "Ref Des/Silkscreen Top")
		(7 "B.SilkS" user "Ref Des/Silkscreen Bottom")
		(1 "F.Mask" user "Board Geometry/Soldermask Top")
		(3 "B.Mask" user "Board Geometry/Soldermask Bottom")
		(17 "Dwgs.User" user "User.Drawings")
		(19 "Cmts.User" user "User.Comments")
		(21 "Eco1.User" user "User.Eco1")
		(23 "Eco2.User" user "User.Eco2")
		(25 "Edge.Cuts" user "Board Geometry/Outline")
		(27 "Margin" user)
		(31 "F.CrtYd" user "Package Geometry/Place Bound Top")
		(29 "B.CrtYd" user "Package Geometry/Place Bound Bottom")
		(35 "F.Fab" user "Ref Des/Assembly Top")
		(33 "B.Fab" user "Ref Des/Assembly Bottom")
	)
	(footprint ""
		(layer "F.Cu")
		(at 338.17179 -284.8991 180)
		(property "Reference" "PU12"
			(at -29.782262 -2.645156 90)
			(unlocked yes)
			(layer "F.SilkS")
			(effects
				(font
					(size 0.7874 0.5842)
					(thickness 0.1524)
				)
				(justify left)
			)
		)
		(property "Value" ""
			(at 0 0 180)
			(layer "F.Fab")
			(effects
				(font
					(size 1.27 1.27)
				)
			)
		)
		(duplicate_pad_numbers_are_jumpers no)
		(fp_line
			(start 2.500122 2.999994)
			(end 2.2987 2.999994)
			(stroke
				(width 0.1524)
				(type default)
			)
			(layer "F.SilkS")
		)
		(fp_line
			(start 2.500122 2.339594)
			(end 2.500122 2.999994)
			(stroke
				(width 0.1524)
				(type default)
			)
			(layer "F.SilkS")
		)
		(fp_line
			(start 2.500122 -2.999994)
			(end 2.500122 -2.44348)
			(stroke
				(width 0.1524)
				(type default)
			)
			(layer "F.SilkS")
		)
		(fp_line
			(start 2.31394 -2.999994)
			(end 2.500122 -2.999994)
			(stroke
				(width 0.1524)
				(type default)
			)
			(layer "F.SilkS")
		)
		(fp_line
			(start -2.2987 2.999994)
			(end -2.500122 2.999994)
			(stroke
				(width 0.1524)
				(type default)
			)
			(layer "F.SilkS")
		)
		(fp_line
			(start -2.500122 2.999994)
			(end -2.500122 2.339594)
			(stroke
				(width 0.1524)
				(type default)
			)
			(layer "F.SilkS")
		)
		(fp_line
			(start -2.500122 0.6604)
			(end -2.500122 0.229108)
			(stroke
				(width 0.1524)
				(type default)
			)
			(layer "F.SilkS")
		)
		(fp_line
			(start -2.500122 -2.529078)
			(end -2.500122 -2.999994)
			(stroke
				(width 0.1524)
				(type default)
			)
			(layer "F.SilkS")
		)
		(fp_line
			(start -2.500122 -2.999994)
			(end -2.24409 -2.999994)
			(stroke
				(width 0.1524)
				(type default)
			)
			(layer "F.SilkS")
		)
		(fp_poly
			(pts
				(xy -3.912616 -4.4958) (xy -4.631182 -3.777234) (xy -3.55346 -3.418078)
			)
			(stroke
				(width 0)
				(type default)
			)
			(fill yes)
			(layer "F.SilkS")
		)
		(fp_line
			(start 2.500122 2.999994)
			(end -2.500122 2.999994)
			(stroke
				(width 0.1)
				(type default)
			)
			(layer "F.Fab")
		)
		(fp_line
			(start 2.500122 -2.999994)
			(end 2.500122 2.999994)
			(stroke
				(width 0.1)
				(type default)
			)
			(layer "F.Fab")
		)
		(fp_line
			(start -2.500122 2.999994)
			(end -2.500122 -2.999994)
			(stroke
				(width 0.1)
				(type default)
			)
			(layer "F.Fab")
		)
		(fp_line
			(start -2.500122 -2.999994)
			(end 2.500122 -2.999994)
			(stroke
				(width 0.1)
				(type default)
			)
			(layer "F.Fab")
		)
		(fp_poly
			(pts
				(xy -4.218432 -2.783078) (xy -4.218432 -1.767078) (xy -3.202432 -2.275078)
			)
			(stroke
				(width 0)
				(type default)
			)
			(fill yes)
			(layer "F.Fab")
		)
		(pad "1" smd rect
			(at -2.400046 -2.275078 270)
			(size 0.2286 0.6096)
			(layers "F.Cu" "F.Mask" "F.Paste")
			(net "SW_P0V8_PEX2_VOS1")
		)
		(pad "2" smd rect
			(at -2.400046 -1.82499 270)
			(size 0.2286 0.6096)
			(layers "F.Cu" "F.Mask" "F.Paste")
			(net "GND")
		)
		(pad "3" smd rect
			(at -2.400046 -1.374902 270)
			(size 0.2286 0.6096)
			(layers "F.Cu" "F.Mask" "F.Paste")
			(net "P0V8_PEX2_VCC1")
		)
		(pad "4" smd rect
			(at -2.400046 -0.925068 270)
			(size 0.2286 0.6096)
			(layers "F.Cu" "F.Mask" "F.Paste")
			(net "P0V8_PEX2_PVCC")
		)
		(pad "5" smd rect
			(at -2.400046 -0.47498 270)
			(size 0.2286 0.6096)
			(layers "F.Cu" "F.Mask" "F.Paste")
			(net "GND")
		)
		(pad "6" smd rect
			(at -2.400046 -0.024892 270)
			(size 0.2286 0.6096)
			(layers "F.Cu" "F.Mask" "F.Paste")
			(net "NC_P0V8_PEX2_PH1_NC1")
		)
		(pad "7_9-20_24" smd circle
			(at 0 1.150112 270)
			(size 0 0)
			(layers "F.Cu" "F.Mask" "F.Paste")
			(net "GND")
		)
		(pad "10_19" smd rect
			(at 0 2.899918 270)
			(size 0.6096 4.318)
			(layers "F.Cu" "F.Mask" "F.Paste")
			(net "SW_P0V8_PEX2_PH1")
		)
		(pad "25_29" smd rect
			(at 1.549908 -1.279906 90)
			(size 2.0574 2.3114)
			(layers "F.Cu" "F.Mask" "F.Paste")
			(net "SW_P12V_P0V8_PEX2_FLT")
		)
		(pad "30" smd rect
			(at 2.05994 -2.899918 180)
			(size 0.2286 0.6096)
			(layers "F.Cu" "F.Mask" "F.Paste")
			(net "SW_P12V_P0V8_PEX2_FLT")
		)
		(pad "31" smd rect
			(at 1.610106 -2.899918 180)
			(size 0.2286 0.6096)
			(layers "F.Cu" "F.Mask" "F.Paste")
			(net "NC_P0V8_PEX2_PH1_NC3")
		)
		(pad "32" smd rect
			(at 1.160018 -2.899918 180)
			(size 0.2286 0.6096)
			(layers "F.Cu" "F.Mask" "F.Paste")
			(net "SW_P0V8_PEX2_PHASE1")
		)
		(pad "33" smd rect
			(at 0.70993 -2.899918 180)
			(size 0.2286 0.6096)
			(layers "F.Cu" "F.Mask" "F.Paste")
			(net "SW_P0V8_PEX2_BOOT1")
		)
		(pad "34" smd rect
			(at 0.260096 -2.899918 180)
			(size 0.2286 0.6096)
			(layers "F.Cu" "F.Mask" "F.Paste")
			(net "P0V8_PEX2_PWM1")
		)
		(pad "35" smd rect
			(at -0.189992 -2.899918 180)
			(size 0.2286 0.6096)
			(layers "F.Cu" "F.Mask" "F.Paste")
			(net "P0V8_PEX2_EN1")
		)
		(pad "36" smd rect
			(at -0.64008 -2.899918 180)
			(size 0.2286 0.6096)
			(layers "F.Cu" "F.Mask" "F.Paste")
			(net "P0V8_PEX2_TSEN")
		)
		(pad "37" smd rect
			(at -1.089914 -2.899918 180)
			(size 0.2286 0.6096)
			(layers "F.Cu" "F.Mask" "F.Paste")
			(net "P0V8_PEX2_LSET1")
		)
		(pad "38" smd rect
			(at -1.540002 -2.899918 180)
			(size 0.2286 0.6096)
			(layers "F.Cu" "F.Mask" "F.Paste")
			(net "P0V8_PEX2_ISEN1")
		)
		(pad "39" smd rect
			(at -1.99009 -2.899918 180)
			(size 0.2286 0.6096)
			(layers "F.Cu" "F.Mask" "F.Paste")
			(net "P0V8_PEX2_VREF")
		)
		(pad "40" smd rect
			(at -0.87503 -1.27508 180)
			(size 1.7526 1.9558)
			(layers "F.Cu" "F.Mask" "F.Paste")
			(net "GND")
		)
		(pad "41" smd rect
			(at -1.525016 0.249936 90)
			(size 0.3048 0.4572)
			(layers "F.Cu" "F.Mask" "F.Paste")
			(net "NC_P0V8_PEX2_PH1_NC2")
		)
		(zone
			(layer "F.Cu")
			(hatch none 0.5)
			(connect_pads
				(clearance 0)
			)
			(min_thickness 0.25)
			(keepout
				(tracks not_allowed)
				(vias allowed)
				(pads allowed)
				(copperpour not_allowed)
				(footprints allowed)
			)
			(placement
				(enabled no)
				(sheetname "")
			)
			(fill
				(thermal_gap 0.5)
				(thermal_bridge_width 0.5)
				(island_removal_mode 0)
			)
			(polygon
				(pts
					(xy 340.671912 -287.899094) (xy 340.671912 -287.149794) (xy 335.671668 -287.149794) (xy 335.671668 -287.899094)
					(xy 335.96199 -287.899094) (xy 335.96199 -287.443418) (xy 340.38159 -287.443418) (xy 340.38159 -287.899094)
				)
			)
		)
	)
	(footprint ""
		(layer "F.Cu")
		(at 138.985244 -92.385642 180)
		(property "Reference" "R1569"
			(at 0 0 180)
			(layer "F.SilkS")
			(hide yes)
			(effects
				(font
					(size 1.27 1.27)
				)
			)
		)
		(property "Value" ""
			(at 0 0 180)
			(layer "F.Fab")
			(effects
				(font
					(size 1.27 1.27)
				)
			)
		)
		(duplicate_pad_numbers_are_jumpers no)
		(fp_line
			(start 0.7874 0.4064)
			(end -0.7874 0.4064)
			(stroke
				(width 0.1524)
				(type default)
			)
			(layer "F.SilkS")
		)
		(fp_line
			(start 0.7874 -0.4064)
			(end 0.7874 0.4064)
			(stroke
				(width 0.1524)
				(type default)
			)
			(layer "F.SilkS")
		)
		(fp_line
			(start -0.7874 0.4064)
			(end -0.7874 -0.4064)
			(stroke
				(width 0.1524)
				(type default)
			)
			(layer "F.SilkS")
		)
		(fp_line
			(start -0.7874 -0.4064)
			(end 0.7874 -0.4064)
			(stroke
				(width 0.1524)
				(type default)
			)
			(layer "F.SilkS")
		)
		(fp_line
			(start 0.67945 0.3048)
			(end 0.120396 0.3048)
			(stroke
				(width 0.1)
				(type default)
			)
			(layer "F.Fab")
		)
		(fp_line
			(start 0.67945 -0.3048)
			(end 0.67945 0.3048)
			(stroke
				(width 0.1)
				(type default)
			)
			(layer "F.Fab")
		)
		(fp_line
			(start 0.12065 -0.2794)
			(end 0.12065 -0.3048)
			(stroke
				(width 0.1)
				(type default)
			)
			(layer "F.Fab")
		)
		(fp_line
			(start 0.12065 -0.3048)
			(end 0.67945 -0.3048)
			(stroke
				(width 0.1)
				(type default)
			)
			(layer "F.Fab")
		)
		(fp_line
			(start 0.120396 0.3048)
			(end 0.120396 0.2794)
			(stroke
				(width 0.1)
				(type default)
			)
			(layer "F.Fab")
		)
		(fp_line
			(start 0.120396 0.2794)
			(end -0.12065 0.2794)
			(stroke
				(width 0.1)
				(type default)
			)
			(layer "F.Fab")
		)
		(fp_line
			(start -0.12065 0.3048)
			(end -0.67945 0.3048)
			(stroke
				(width 0.1)
				(type default)
			)
			(layer "F.Fab")
		)
		(fp_line
			(start -0.12065 0.2794)
			(end -0.12065 0.3048)
			(stroke
				(width 0.1)
				(type default)
			)
			(layer "F.Fab")
		)
		(fp_line
			(start -0.12065 -0.2794)
			(end 0.12065 -0.2794)
			(stroke
				(width 0.1)
				(type default)
			)
			(layer "F.Fab")
		)
		(fp_line
			(start -0.12065 -0.305054)
			(end -0.12065 -0.2794)
			(stroke
				(width 0.1)
				(type default)
			)
			(layer "F.Fab")
		)
		(fp_line
			(start -0.67945 0.3048)
			(end -0.67945 -0.305054)
			(stroke
				(width 0.1)
				(type default)
			)
			(layer "F.Fab")
		)
		(fp_line
			(start -0.67945 -0.305054)
			(end -0.12065 -0.305054)
			(stroke
				(width 0.1)
				(type default)
			)
			(layer "F.Fab")
		)
		(pad "1" smd circle
			(at -0.40005 0 180)
			(size 0 0)
			(layers "F.Cu" "F.Mask" "F.Paste")
			(net "P3V3_AUX")
		)
		(pad "2" smd circle
			(at 0.40005 0 180)
			(size 0 0)
			(layers "F.Cu" "F.Mask" "F.Paste")
			(net "SMB_BIC_I2C9_MUX0_SSD6_R_SDA")
		)
	)
	(footprint ""
		(layer "F.Cu")
		(at 238.324898 -84.351368 90)
		(property "Reference" "R6624"
			(at 0 0 90)
			(layer "F.SilkS")
			(hide yes)
			(effects
				(font
					(size 1.27 1.27)
				)
			)
		)
		(property "Value" ""
			(at 0 0 90)
			(layer "F.Fab")
			(effects
				(font
					(size 1.27 1.27)
				)
			)
		)
		(duplicate_pad_numbers_are_jumpers no)
		(fp_line
			(start 0.7874 -0.4064)
			(end 0.7874 0.4064)
			(stroke
				(width 0.1524)
				(type default)
			)
			(layer "F.SilkS")
		)
		(fp_line
			(start -0.7874 -0.4064)
			(end 0.7874 -0.4064)
			(stroke
				(width 0.1524)
				(type default)
			)
			(layer "F.SilkS")
		)
		(fp_line
			(start -0.018288 0.4064)
			(end -0.7874 0.4064)
			(stroke
				(width 0.1524)
				(type default)
			)
			(layer "F.SilkS")
		)
		(fp_line
			(start -0.12065 -0.305054)
			(end -0.12065 -0.2794)
			(stroke
				(width 0.1)
				(type default)
			)
			(layer "F.Fab")
		)
		(fp_line
			(start -0.67945 -0.305054)
			(end -0.12065 -0.305054)
			(stroke
				(width 0.1)
				(type default)
			)
			(layer "F.Fab")
		)
		(fp_line
			(start 0.67945 -0.3048)
			(end 0.67945 0.3048)
			(stroke
				(width 0.1)
				(type default)
			)
			(layer "F.Fab")
		)
		(fp_line
			(start 0.12065 -0.3048)
			(end 0.67945 -0.3048)
			(stroke
				(width 0.1)
				(type default)
			)
			(layer "F.Fab")
		)
		(fp_line
			(start 0.12065 -0.2794)
			(end 0.12065 -0.3048)
			(stroke
				(width 0.1)
				(type default)
			)
			(layer "F.Fab")
		)
		(fp_line
			(start -0.12065 -0.2794)
			(end 0.12065 -0.2794)
			(stroke
				(width 0.1)
				(type default)
			)
			(layer "F.Fab")
		)
		(fp_line
			(start 0.120396 0.2794)
			(end -0.12065 0.2794)
			(stroke
				(width 0.1)
				(type default)
			)
			(layer "F.Fab")
		)
		(fp_line
			(start -0.12065 0.2794)
			(end -0.12065 0.3048)
			(stroke
				(width 0.1)
				(type default)
			)
			(layer "F.Fab")
		)
		(fp_line
			(start 0.67945 0.3048)
			(end 0.120396 0.3048)
			(stroke
				(width 0.1)
				(type default)
			)
			(layer "F.Fab")
		)
		(fp_line
			(start 0.120396 0.3048)
			(end 0.120396 0.2794)
			(stroke
				(width 0.1)
				(type default)
			)
			(layer "F.Fab")
		)
		(fp_line
			(start -0.12065 0.3048)
			(end -0.67945 0.3048)
			(stroke
				(width 0.1)
				(type default)
			)
			(layer "F.Fab")
		)
		(fp_line
			(start -0.67945 0.3048)
			(end -0.67945 -0.305054)
			(stroke
				(width 0.1)
				(type default)
			)
			(layer "F.Fab")
		)
		(pad "1" smd rect
			(at -0.40005 0 270)
			(size 0.4572 0.508)
			(layers "F.Cu" "F.Mask" "F.Paste")
			(net "USB2_CP2108_CLI_DN")
		)
		(pad "2" smd rect
			(at 0.40005 0 270)
			(size 0.4572 0.508)
			(layers "F.Cu" "F.Mask" "F.Paste")
			(net "USB2_FT4232_CLI_R_DN")
		)
	)
)
